# S9S_MB_2U (Grand Teton) — schematic netlist excerpt (pin names and nets, part order shuffled) for the footprints in the layout excerpt that follows; sources: Cadence DE-HDL packaged netlist, KiCad conversion of 03242023_DA0F0TMBIJ0_F0T_Motherboard_J_brd_V01_OCP.brd

R2983  Q_RES  0 5% CHIP  pkg 0402LF  page 227 : A = SMB_IOEXP_3V3AUX_SDA ; B = SMB_IOEXP_3V3AUX_SDA_R1
R3466  Q_RES  10K 1% CHIP  pkg 0402LF  page 149 : A = RST_PERST_2_SWB_BUF_R_N ; B = GND
H92  HOLE  EMPTY  pkg TH  page 311 : \1\ = GND

(kicad_pcb
	(version 20260206)
	(generator "pcbnew")
	(generator_version "10.0")
	(general
		(thickness 1.6)
		(legacy_teardrops no)
	)
	(paper "A4")
	(title_block
		(title "03242023_DA0F0TMBIJ0_F0T_Motherboard_J_brd_V01_OCP.brd")
		(comment 1 "Grand Teton / footprints 488-490 of 6105")
	)
	(layers
		(0 "F.Cu" signal "TOP")
		(4 "In1.Cu" signal "GND")
		(6 "In2.Cu" signal "IN1")
		(8 "In3.Cu" signal "GND1")
		(10 "In4.Cu" signal "IN2")
		(12 "In5.Cu" signal "GND2")
		(14 "In6.Cu" signal "IN3")
		(16 "In7.Cu" signal "GND3")
		(18 "In8.Cu" signal "VCC")
		(20 "In9.Cu" signal "VCC1")
		(22 "In10.Cu" signal "GND4")
		(24 "In11.Cu" signal "IN4")
		(26 "In12.Cu" signal "GND5")
		(28 "In13.Cu" signal "IN5")
		(30 "In14.Cu" signal "GND6")
		(32 "In15.Cu" signal "IN6")
		(34 "In16.Cu" signal "GND7")
		(2 "B.Cu" signal "BOTTOM")
		(9 "F.Adhes" user "F.Adhesive")
		(11 "B.Adhes" user "B.Adhesive")
		(13 "F.Paste" user "Package Geometry/Pastemask Top")
		(15 "B.Paste" user "Package Geometry/Pastemask Bottom")
		(5 "F.SilkS" user "Ref Des/Silkscreen Top")
		(7 "B.SilkS" user "Ref Des/Silkscreen Bottom")
		(1 "F.Mask" user "Board Geometry/Soldermask Top")
		(3 "B.Mask" user "Board Geometry/Soldermask Bottom")
		(17 "Dwgs.User" user "User.Drawings")
		(19 "Cmts.User" user "User.Comments")
		(21 "Eco1.User" user "User.Eco1")
		(23 "Eco2.User" user "User.Eco2")
		(25 "Edge.Cuts" user "Board Geometry/Outline")
		(27 "Margin" user)
		(31 "F.CrtYd" user "Package Geometry/Place Bound Top")
		(29 "B.CrtYd" user "Package Geometry/Place Bound Bottom")
		(35 "F.Fab" user "Ref Des/Assembly Top")
		(33 "B.Fab" user "Ref Des/Assembly Bottom")
	)
	(footprint ""
		(layer "F.Cu")
		(at 31.29788 -433.923948)
		(property "Reference" "R3466"
			(at 0 0 0)
			(layer "F.SilkS")
			(hide yes)
			(effects
				(font
					(size 1.27 1.27)
				)
			)
		)
		(property "Value" ""
			(at 0 0 0)
			(layer "F.Fab")
			(effects
				(font
					(size 1.27 1.27)
				)
			)
		)
		(duplicate_pad_numbers_are_jumpers no)
		(fp_line
			(start -0.7874 -0.4064)
			(end 0.7874 -0.4064)
			(stroke
				(width 0.1524)
				(type default)
			)
			(layer "F.SilkS")
		)
		(fp_line
			(start -0.7874 0.4064)
			(end -0.7874 -0.4064)
			(stroke
				(width 0.1524)
				(type default)
			)
			(layer "F.SilkS")
		)
		(fp_line
			(start 0.7874 -0.4064)
			(end 0.7874 0.4064)
			(stroke
				(width 0.1524)
				(type default)
			)
			(layer "F.SilkS")
		)
		(fp_line
			(start 0.7874 0.4064)
			(end -0.7874 0.4064)
			(stroke
				(width 0.1524)
				(type default)
			)
			(layer "F.SilkS")
		)
		(fp_line
			(start -0.67945 -0.305054)
			(end -0.12065 -0.305054)
			(stroke
				(width 0.1)
				(type default)
			)
			(layer "F.Fab")
		)
		(fp_line
			(start -0.67945 0.3048)
			(end -0.67945 -0.305054)
			(stroke
				(width 0.1)
				(type default)
			)
			(layer "F.Fab")
		)
		(fp_line
			(start -0.12065 -0.305054)
			(end -0.12065 -0.2794)
			(stroke
				(width 0.1)
				(type default)
			)
			(layer "F.Fab")
		)
		(fp_line
			(start -0.12065 -0.2794)
			(end 0.12065 -0.2794)
			(stroke
				(width 0.1)
				(type default)
			)
			(layer "F.Fab")
		)
		(fp_line
			(start -0.12065 0.2794)
			(end -0.12065 0.3048)
			(stroke
				(width 0.1)
				(type default)
			)
			(layer "F.Fab")
		)
		(fp_line
			(start -0.12065 0.3048)
			(end -0.67945 0.3048)
			(stroke
				(width 0.1)
				(type default)
			)
			(layer "F.Fab")
		)
		(fp_line
			(start 0.120396 0.2794)
			(end -0.12065 0.2794)
			(stroke
				(width 0.1)
				(type default)
			)
			(layer "F.Fab")
		)
		(fp_line
			(start 0.120396 0.3048)
			(end 0.120396 0.2794)
			(stroke
				(width 0.1)
				(type default)
			)
			(layer "F.Fab")
		)
		(fp_line
			(start 0.12065 -0.3048)
			(end 0.67945 -0.3048)
			(stroke
				(width 0.1)
				(type default)
			)
			(layer "F.Fab")
		)
		(fp_line
			(start 0.12065 -0.2794)
			(end 0.12065 -0.3048)
			(stroke
				(width 0.1)
				(type default)
			)
			(layer "F.Fab")
		)
		(fp_line
			(start 0.67945 -0.3048)
			(end 0.67945 0.3048)
			(stroke
				(width 0.1)
				(type default)
			)
			(layer "F.Fab")
		)
		(fp_line
			(start 0.67945 0.3048)
			(end 0.120396 0.3048)
			(stroke
				(width 0.1)
				(type default)
			)
			(layer "F.Fab")
		)
		(pad "1" smd circle
			(at -0.40005 0)
			(size 0 0)
			(layers "F.Cu" "F.Mask" "F.Paste")
			(net "RST_PERST_2_SWB_BUF_R_N")
		)
		(pad "2" smd circle
			(at 0.40005 0)
			(size 0 0)
			(layers "F.Cu" "F.Mask" "F.Paste")
			(net "GND")
		)
	)
	(footprint ""
		(layer "F.Cu")
		(at 12.530582 -423.629836 -90)
		(property "Reference" "R2983"
			(at 0 0 270)
			(layer "F.SilkS")
			(hide yes)
			(effects
				(font
					(size 1.27 1.27)
				)
			)
		)
		(property "Value" ""
			(at 0 0 270)
			(layer "F.Fab")
			(effects
				(font
					(size 1.27 1.27)
				)
			)
		)
		(duplicate_pad_numbers_are_jumpers no)
		(fp_line
			(start -0.7874 0.4064)
			(end -0.7874 -0.4064)
			(stroke
				(width 0.1524)
				(type default)
			)
			(layer "F.SilkS")
		)
		(fp_line
			(start 0.7874 0.4064)
			(end -0.7874 0.4064)
			(stroke
				(width 0.1524)
				(type default)
			)
			(layer "F.SilkS")
		)
		(fp_line
			(start -0.7874 -0.4064)
			(end 0.7874 -0.4064)
			(stroke
				(width 0.1524)
				(type default)
			)
			(layer "F.SilkS")
		)
		(fp_line
			(start 0.7874 -0.4064)
			(end 0.7874 0.4064)
			(stroke
				(width 0.1524)
				(type default)
			)
			(layer "F.SilkS")
		)
		(fp_line
			(start -0.67945 0.3048)
			(end -0.67945 -0.305054)
			(stroke
				(width 0.1)
				(type default)
			)
			(layer "F.Fab")
		)
		(fp_line
			(start -0.12065 0.3048)
			(end -0.67945 0.3048)
			(stroke
				(width 0.1)
				(type default)
			)
			(layer "F.Fab")
		)
		(fp_line
			(start 0.120396 0.3048)
			(end 0.120396 0.2794)
			(stroke
				(width 0.1)
				(type default)
			)
			(layer "F.Fab")
		)
		(fp_line
			(start 0.67945 0.3048)
			(end 0.120396 0.3048)
			(stroke
				(width 0.1)
				(type default)
			)
			(layer "F.Fab")
		)
		(fp_line
			(start -0.12065 0.2794)
			(end -0.12065 0.3048)
			(stroke
				(width 0.1)
				(type default)
			)
			(layer "F.Fab")
		)
		(fp_line
			(start 0.120396 0.2794)
			(end -0.12065 0.2794)
			(stroke
				(width 0.1)
				(type default)
			)
			(layer "F.Fab")
		)
		(fp_line
			(start -0.12065 -0.2794)
			(end 0.12065 -0.2794)
			(stroke
				(width 0.1)
				(type default)
			)
			(layer "F.Fab")
		)
		(fp_line
			(start 0.12065 -0.2794)
			(end 0.12065 -0.3048)
			(stroke
				(width 0.1)
				(type default)
			)
			(layer "F.Fab")
		)
		(fp_line
			(start 0.12065 -0.3048)
			(end 0.67945 -0.3048)
			(stroke
				(width 0.1)
				(type default)
			)
			(layer "F.Fab")
		)
		(fp_line
			(start 0.67945 -0.3048)
			(end 0.67945 0.3048)
			(stroke
				(width 0.1)
				(type default)
			)
			(layer "F.Fab")
		)
		(fp_line
			(start -0.67945 -0.305054)
			(end -0.12065 -0.305054)
			(stroke
				(width 0.1)
				(type default)
			)
			(layer "F.Fab")
		)
		(fp_line
			(start -0.12065 -0.305054)
			(end -0.12065 -0.2794)
			(stroke
				(width 0.1)
				(type default)
			)
			(layer "F.Fab")
		)
		(pad "1" smd circle
			(at -0.40005 0 270)
			(size 0 0)
			(layers "F.Cu" "F.Mask" "F.Paste")
			(net "SMB_IOEXP_3V3AUX_SDA")
		)
		(pad "2" smd circle
			(at 0.40005 0 270)
			(size 0 0)
			(layers "F.Cu" "F.Mask" "F.Paste")
			(net "SMB_IOEXP_3V3AUX_SDA_R1")
		)
	)
	(footprint ""
		(layer "F.Cu")
		(at 100.50018 -435.600094)
		(property "Reference" "H92"
			(at -5.01396 -4.694428 0)
			(unlocked yes)
			(layer "F.SilkS")
			(effects
				(font
					(size 0.7874 0.5842)
					(thickness 0.1524)
				)
				(justify left)
			)
		)
		(property "Value" ""
			(at 0 0 0)
			(layer "F.Fab")
			(effects
				(font
					(size 1.27 1.27)
				)
			)
		)
		(duplicate_pad_numbers_are_jumpers no)
		(pad "1" thru_hole circle
			(at 0 0)
			(size 10.0076 10.0076)
			(drill 5.6134)
			(layers "*.Cu" "*.Mask")
			(remove_unused_layers no)
			(net "GND")
			(clearance -1.9431)
		)
	)
)
